(kicad_pcb
	(version 20260206)
	(generator "pcbnew")
	(generator_version "10.0")
	(general
		(thickness 1.6)
		(legacy_teardrops no)
	)
	(paper "A4")
	(title_block
		(title "peb — Lightning_PEB_BRD.brd")
		(comment 1 "Lightning (Wiwynn / Facebook NVMe JBOF) / footprints 2387-2394 of 2563")
	)
	(layers
		(0 "F.Cu" signal "TOP")
		(4 "In1.Cu" signal "L2GND")
		(6 "In2.Cu" signal "L3")
		(8 "In3.Cu" signal "L4VCC")
		(10 "In4.Cu" signal "L5VCC")
		(12 "In5.Cu" signal "L6")
		(14 "In6.Cu" signal "L7GND")
		(2 "B.Cu" signal "BOTTOM")
		(9 "F.Adhes" user "F.Adhesive")
		(11 "B.Adhes" user "B.Adhesive")
		(13 "F.Paste" user "Package Geometry/Pastemask Top")
		(15 "B.Paste" user "Package Geometry/Pastemask Bottom")
		(5 "F.SilkS" user "Ref Des/Silkscreen Top")
		(7 "B.SilkS" user "Ref Des/Silkscreen Bottom")
		(1 "F.Mask" user "Board Geometry/Soldermask Top")
		(3 "B.Mask" user "Board Geometry/Soldermask Bottom")
		(17 "Dwgs.User" user "User.Drawings")
		(19 "Cmts.User" user "User.Comments")
		(21 "Eco1.User" user "User.Eco1")
		(23 "Eco2.User" user "User.Eco2")
		(25 "Edge.Cuts" user "Board Geometry/Outline")
		(27 "Margin" user)
		(31 "F.CrtYd" user "Package Geometry/Place Bound Top")
		(29 "B.CrtYd" user "Package Geometry/Place Bound Bottom")
		(35 "F.Fab" user "Ref Des/Assembly Top")
		(33 "B.Fab" user "Ref Des/Assembly Bottom")
	)
	(footprint ""
		(layer "B.Cu")
		(at 124.944124 -196.443092 180)
		(property "Reference" "R525"
			(at 0 0 0)
			(layer "B.SilkS")
			(hide yes)
			(effects
				(font
					(size 1.27 1.27)
				)
				(justify mirror)
			)
		)
		(property "Value" "10KR2F-2-GP"
			(at -0.064008 -3.993896 180)
			(unlocked yes)
			(layer "B.Fab")
			(hide yes)
			(effects
				(font
					(size 1.016 1.016)
					(thickness 0.1524)
				)
				(justify mirror)
			)
		)
		(property "Device Type" "R402H16"
			(at -0.064008 -5.517896 180)
			(unlocked yes)
			(layer "B.Fab")
			(hide yes)
			(effects
				(font
					(size 1.016 1.016)
					(thickness 0.1524)
				)
				(justify mirror)
			)
		)
		(duplicate_pad_numbers_are_jumpers no)
		(fp_line
			(start 0.508 -0.9398)
			(end 0.508 0.9398)
			(stroke
				(width 0.1524)
				(type default)
			)
			(layer "B.SilkS")
		)
		(fp_line
			(start -0.508 -0.9398)
			(end 0.508 -0.9398)
			(stroke
				(width 0.1524)
				(type default)
			)
			(layer "B.SilkS")
		)
		(fp_rect
			(start 0.508 0.9398)
			(end -0.508 -0.9398)
			(stroke
				(width 0)
				(type default)
			)
			(fill no)
			(layer "B.CrtYd")
		)
		(fp_rect
			(start 0.508 0.9398)
			(end -0.508 -0.9398)
			(stroke
				(width 0)
				(type default)
			)
			(fill no)
			(layer "B.Fab")
		)
		(pad "1" smd custom
			(at 0 -0.4445)
			(size 0.1397 0.1397)
			(layers "B.Cu" "B.Mask" "B.Paste")
			(net "P3V3_STBY")
			(options
				(clearance outline)
				(anchor circle)
			)
			(primitives
				(gr_poly
					(pts
						(arc
							(start -0.1778 0.2794)
							(mid -0.249642 0.249642)
							(end -0.2794 0.1778)
						)
						(arc
							(start -0.2794 -0.1778)
							(mid -0.249642 -0.249642)
							(end -0.1778 -0.2794)
						)
						(arc
							(start 0.1778 -0.2794)
							(mid 0.249642 -0.249642)
							(end 0.2794 -0.1778)
						)
						(arc
							(start 0.2794 0.1778)
							(mid 0.249642 0.249642)
							(end 0.1778 0.2794)
						)
					)
					(width 0)
					(fill yes)
				)
			)
		)
		(pad "2" smd custom
			(at 0 0.4445)
			(size 0.1397 0.1397)
			(layers "B.Cu" "B.Mask" "B.Paste")
			(net "IOEXP2_AD2")
			(options
				(clearance outline)
				(anchor circle)
			)
			(primitives
				(gr_poly
					(pts
						(arc
							(start -0.1778 0.2794)
							(mid -0.249642 0.249642)
							(end -0.2794 0.1778)
						)
						(arc
							(start -0.2794 -0.1778)
							(mid -0.249642 -0.249642)
							(end -0.1778 -0.2794)
						)
						(arc
							(start 0.1778 -0.2794)
							(mid 0.249642 -0.249642)
							(end 0.2794 -0.1778)
						)
						(arc
							(start 0.2794 0.1778)
							(mid 0.249642 0.249642)
							(end 0.1778 0.2794)
						)
					)
					(width 0)
					(fill yes)
				)
			)
		)
	)
	(footprint ""
		(layer "B.Cu")
		(at 239.395 -20.447)
		(property "Reference" "R795"
			(at 0 0 0)
			(layer "B.SilkS")
			(hide yes)
			(effects
				(font
					(size 1.27 1.27)
				)
				(justify mirror)
			)
		)
		(property "Value" "4K7R2F-GP"
			(at -0.064008 -3.993896 0)
			(unlocked yes)
			(layer "B.Fab")
			(hide yes)
			(effects
				(font
					(size 1.016 1.016)
					(thickness 0.1524)
				)
				(justify mirror)
			)
		)
		(property "Device Type" "R402H16"
			(at -0.064008 -5.517896 0)
			(unlocked yes)
			(layer "B.Fab")
			(hide yes)
			(effects
				(font
					(size 1.016 1.016)
					(thickness 0.1524)
				)
				(justify mirror)
			)
		)
		(duplicate_pad_numbers_are_jumpers no)
		(fp_line
			(start -0.508 -0.9398)
			(end 0.508 -0.9398)
			(stroke
				(width 0.1524)
				(type default)
			)
			(layer "B.SilkS")
		)
		(fp_line
			(start 0.508 -0.9398)
			(end 0.508 0.9398)
			(stroke
				(width 0.1524)
				(type default)
			)
			(layer "B.SilkS")
		)
		(fp_rect
			(start 0.508 0.9398)
			(end -0.508 -0.9398)
			(stroke
				(width 0)
				(type default)
			)
			(fill no)
			(layer "B.CrtYd")
		)
		(fp_rect
			(start 0.508 0.9398)
			(end -0.508 -0.9398)
			(stroke
				(width 0)
				(type default)
			)
			(fill no)
			(layer "B.Fab")
		)
		(pad "1" smd custom
			(at 0 -0.4445 180)
			(size 0.1397 0.1397)
			(layers "B.Cu" "B.Mask" "B.Paste")
			(net "BOOTSTRAP1")
			(options
				(clearance outline)
				(anchor circle)
			)
			(primitives
				(gr_poly
					(pts
						(arc
							(start -0.1778 0.2794)
							(mid -0.249642 0.249642)
							(end -0.2794 0.1778)
						)
						(arc
							(start -0.2794 -0.1778)
							(mid -0.249642 -0.249642)
							(end -0.1778 -0.2794)
						)
						(arc
							(start 0.1778 -0.2794)
							(mid 0.249642 -0.249642)
							(end 0.2794 -0.1778)
						)
						(arc
							(start 0.2794 0.1778)
							(mid 0.249642 0.249642)
							(end 0.1778 0.2794)
						)
					)
					(width 0)
					(fill yes)
				)
			)
		)
		(pad "2" smd custom
			(at 0 0.4445 180)
			(size 0.1397 0.1397)
			(layers "B.Cu" "B.Mask" "B.Paste")
			(net "DUT_VDDO")
			(options
				(clearance outline)
				(anchor circle)
			)
			(primitives
				(gr_poly
					(pts
						(arc
							(start -0.1778 0.2794)
							(mid -0.249642 0.249642)
							(end -0.2794 0.1778)
						)
						(arc
							(start -0.2794 -0.1778)
							(mid -0.249642 -0.249642)
							(end -0.1778 -0.2794)
						)
						(arc
							(start 0.1778 -0.2794)
							(mid 0.249642 -0.249642)
							(end 0.2794 -0.1778)
						)
						(arc
							(start 0.2794 0.1778)
							(mid 0.249642 0.249642)
							(end 0.1778 0.2794)
						)
					)
					(width 0)
					(fill yes)
				)
			)
		)
	)
	(footprint ""
		(layer "B.Cu")
		(at 57.023 -140.843 -90)
		(property "Reference" "R220"
			(at 0 0 90)
			(layer "B.SilkS")
			(hide yes)
			(effects
				(font
					(size 1.27 1.27)
				)
				(justify mirror)
			)
		)
		(property "Value" "4K7R2F-GP"
			(at -0.064008 -3.993896 270)
			(unlocked yes)
			(layer "B.Fab")
			(hide yes)
			(effects
				(font
					(size 1.016 1.016)
					(thickness 0.1524)
				)
				(justify mirror)
			)
		)
		(property "Device Type" "R402H16"
			(at -0.064008 -5.517896 270)
			(unlocked yes)
			(layer "B.Fab")
			(hide yes)
			(effects
				(font
					(size 1.016 1.016)
					(thickness 0.1524)
				)
				(justify mirror)
			)
		)
		(duplicate_pad_numbers_are_jumpers no)
		(fp_line
			(start -0.508 -0.9398)
			(end 0.508 -0.9398)
			(stroke
				(width 0.1524)
				(type default)
			)
			(layer "B.SilkS")
		)
		(fp_line
			(start 0.508 -0.9398)
			(end 0.508 0.9398)
			(stroke
				(width 0.1524)
				(type default)
			)
			(layer "B.SilkS")
		)
		(fp_rect
			(start 0.508 0.9398)
			(end -0.508 -0.9398)
			(stroke
				(width 0)
				(type default)
			)
			(fill no)
			(layer "B.CrtYd")
		)
		(fp_rect
			(start 0.508 0.9398)
			(end -0.508 -0.9398)
			(stroke
				(width 0)
				(type default)
			)
			(fill no)
			(layer "B.Fab")
		)
		(pad "1" smd custom
			(at 0 -0.4445 90)
			(size 0.1397 0.1397)
			(layers "B.Cu" "B.Mask" "B.Paste")
			(net "BMC_SELF_TRAY")
			(options
				(clearance outline)
				(anchor circle)
			)
			(primitives
				(gr_poly
					(pts
						(arc
							(start -0.1778 0.2794)
							(mid -0.249642 0.249642)
							(end -0.2794 0.1778)
						)
						(arc
							(start -0.2794 -0.1778)
							(mid -0.249642 -0.249642)
							(end -0.1778 -0.2794)
						)
						(arc
							(start 0.1778 -0.2794)
							(mid 0.249642 -0.249642)
							(end 0.2794 -0.1778)
						)
						(arc
							(start 0.2794 0.1778)
							(mid 0.249642 0.249642)
							(end 0.1778 0.2794)
						)
					)
					(width 0)
					(fill yes)
				)
			)
		)
		(pad "2" smd custom
			(at 0 0.4445 90)
			(size 0.1397 0.1397)
			(layers "B.Cu" "B.Mask" "B.Paste")
			(net "P3V3_STBY")
			(options
				(clearance outline)
				(anchor circle)
			)
			(primitives
				(gr_poly
					(pts
						(arc
							(start -0.1778 0.2794)
							(mid -0.249642 0.249642)
							(end -0.2794 0.1778)
						)
						(arc
							(start -0.2794 -0.1778)
							(mid -0.249642 -0.249642)
							(end -0.1778 -0.2794)
						)
						(arc
							(start 0.1778 -0.2794)
							(mid 0.249642 -0.249642)
							(end 0.2794 -0.1778)
						)
						(arc
							(start 0.2794 0.1778)
							(mid 0.249642 0.249642)
							(end 0.1778 0.2794)
						)
					)
					(width 0)
					(fill yes)
				)
			)
		)
	)
	(footprint ""
		(layer "B.Cu")
		(at 222.8342 -7.366)
		(property "Reference" "R674"
			(at 0 0 0)
			(layer "B.SilkS")
			(hide yes)
			(effects
				(font
					(size 1.27 1.27)
				)
				(justify mirror)
			)
		)
		(property "Value" "100KR2F-L1-GP"
			(at -0.064008 -3.993896 0)
			(unlocked yes)
			(layer "B.Fab")
			(hide yes)
			(effects
				(font
					(size 1.016 1.016)
					(thickness 0.1524)
				)
				(justify mirror)
			)
		)
		(property "Device Type" "R402H16"
			(at -0.064008 -5.517896 0)
			(unlocked yes)
			(layer "B.Fab")
			(hide yes)
			(effects
				(font
					(size 1.016 1.016)
					(thickness 0.1524)
				)
				(justify mirror)
			)
		)
		(duplicate_pad_numbers_are_jumpers no)
		(fp_line
			(start -0.508 -0.9398)
			(end 0.508 -0.9398)
			(stroke
				(width 0.1524)
				(type default)
			)
			(layer "B.SilkS")
		)
		(fp_line
			(start 0.508 -0.9398)
			(end 0.508 0.9398)
			(stroke
				(width 0.1524)
				(type default)
			)
			(layer "B.SilkS")
		)
		(fp_rect
			(start 0.508 0.9398)
			(end -0.508 -0.9398)
			(stroke
				(width 0)
				(type default)
			)
			(fill no)
			(layer "B.CrtYd")
		)
		(fp_rect
			(start 0.508 0.9398)
			(end -0.508 -0.9398)
			(stroke
				(width 0)
				(type default)
			)
			(fill no)
			(layer "B.Fab")
		)
		(pad "1" smd custom
			(at 0 -0.4445 180)
			(size 0.1397 0.1397)
			(layers "B.Cu" "B.Mask" "B.Paste")
			(net "HOST1_RST_N")
			(options
				(clearance outline)
				(anchor circle)
			)
			(primitives
				(gr_poly
					(pts
						(arc
							(start -0.1778 0.2794)
							(mid -0.249642 0.249642)
							(end -0.2794 0.1778)
						)
						(arc
							(start -0.2794 -0.1778)
							(mid -0.249642 -0.249642)
							(end -0.1778 -0.2794)
						)
						(arc
							(start 0.1778 -0.2794)
							(mid 0.249642 -0.249642)
							(end 0.2794 -0.1778)
						)
						(arc
							(start 0.2794 0.1778)
							(mid 0.249642 0.249642)
							(end 0.1778 0.2794)
						)
					)
					(width 0)
					(fill yes)
				)
			)
		)
		(pad "2" smd custom
			(at 0 0.4445 180)
			(size 0.1397 0.1397)
			(layers "B.Cu" "B.Mask" "B.Paste")
			(net "GND")
			(options
				(clearance outline)
				(anchor circle)
			)
			(primitives
				(gr_poly
					(pts
						(arc
							(start -0.1778 0.2794)
							(mid -0.249642 0.249642)
							(end -0.2794 0.1778)
						)
						(arc
							(start -0.2794 -0.1778)
							(mid -0.249642 -0.249642)
							(end -0.1778 -0.2794)
						)
						(arc
							(start 0.1778 -0.2794)
							(mid 0.249642 -0.249642)
							(end 0.2794 -0.1778)
						)
						(arc
							(start 0.2794 0.1778)
							(mid 0.249642 0.249642)
							(end 0.1778 0.2794)
						)
					)
					(width 0)
					(fill yes)
				)
			)
		)
	)
	(footprint ""
		(layer "B.Cu")
		(at 51.689 -181.483 180)
		(property "Reference" "R901"
			(at 0 0 0)
			(layer "B.SilkS")
			(hide yes)
			(effects
				(font
					(size 1.27 1.27)
				)
				(justify mirror)
			)
		)
		(property "Value" "0R2J-2-GP"
			(at -0.064008 -3.993896 180)
			(unlocked yes)
			(layer "B.Fab")
			(hide yes)
			(effects
				(font
					(size 1.016 1.016)
					(thickness 0.1524)
				)
				(justify mirror)
			)
		)
		(property "Device Type" "R402H16"
			(at -0.064008 -5.517896 180)
			(unlocked yes)
			(layer "B.Fab")
			(hide yes)
			(effects
				(font
					(size 1.016 1.016)
					(thickness 0.1524)
				)
				(justify mirror)
			)
		)
		(duplicate_pad_numbers_are_jumpers no)
		(fp_line
			(start 0.508 -0.9398)
			(end 0.508 0.9398)
			(stroke
				(width 0.1524)
				(type default)
			)
			(layer "B.SilkS")
		)
		(fp_line
			(start -0.508 -0.9398)
			(end 0.508 -0.9398)
			(stroke
				(width 0.1524)
				(type default)
			)
			(layer "B.SilkS")
		)
		(fp_rect
			(start 0.508 0.9398)
			(end -0.508 -0.9398)
			(stroke
				(width 0)
				(type default)
			)
			(fill no)
			(layer "B.CrtYd")
		)
		(fp_rect
			(start 0.508 0.9398)
			(end -0.508 -0.9398)
			(stroke
				(width 0)
				(type default)
			)
			(fill no)
			(layer "B.Fab")
		)
		(pad "1" smd custom
			(at 0 -0.4445)
			(size 0.1397 0.1397)
			(layers "B.Cu" "B.Mask" "B.Paste")
			(net "BMC_I2C8_CLKBUF1_SCL")
			(options
				(clearance outline)
				(anchor circle)
			)
			(primitives
				(gr_poly
					(pts
						(arc
							(start -0.1778 0.2794)
							(mid -0.249642 0.249642)
							(end -0.2794 0.1778)
						)
						(arc
							(start -0.2794 -0.1778)
							(mid -0.249642 -0.249642)
							(end -0.1778 -0.2794)
						)
						(arc
							(start 0.1778 -0.2794)
							(mid 0.249642 -0.249642)
							(end 0.2794 -0.1778)
						)
						(arc
							(start 0.2794 0.1778)
							(mid 0.249642 0.249642)
							(end 0.1778 0.2794)
						)
					)
					(width 0)
					(fill yes)
				)
			)
		)
		(pad "2" smd custom
			(at 0 0.4445)
			(size 0.1397 0.1397)
			(layers "B.Cu" "B.Mask" "B.Paste")
			(net "BUF_I2C8_CLKBUF1_SCL")
			(options
				(clearance outline)
				(anchor circle)
			)
			(primitives
				(gr_poly
					(pts
						(arc
							(start -0.1778 0.2794)
							(mid -0.249642 0.249642)
							(end -0.2794 0.1778)
						)
						(arc
							(start -0.2794 -0.1778)
							(mid -0.249642 -0.249642)
							(end -0.1778 -0.2794)
						)
						(arc
							(start 0.1778 -0.2794)
							(mid 0.249642 -0.249642)
							(end 0.2794 -0.1778)
						)
						(arc
							(start 0.2794 0.1778)
							(mid 0.249642 0.249642)
							(end 0.1778 0.2794)
						)
					)
					(width 0)
					(fill yes)
				)
			)
		)
	)
	(footprint ""
		(layer "B.Cu")
		(at 33.885886 -108.289598 90)
		(property "Reference" "R288"
			(at 0 0 90)
			(layer "B.SilkS")
			(hide yes)
			(effects
				(font
					(size 1.27 1.27)
				)
				(justify mirror)
			)
		)
		(property "Value" "47KR2F-GP"
			(at -0.064008 -3.993896 90)
			(unlocked yes)
			(layer "B.Fab")
			(hide yes)
			(effects
				(font
					(size 1.016 1.016)
					(thickness 0.1524)
				)
				(justify mirror)
			)
		)
		(property "Device Type" "R402H16"
			(at -0.064008 -5.517896 90)
			(unlocked yes)
			(layer "B.Fab")
			(hide yes)
			(effects
				(font
					(size 1.016 1.016)
					(thickness 0.1524)
				)
				(justify mirror)
			)
		)
		(duplicate_pad_numbers_are_jumpers no)
		(fp_line
			(start 0.508 -0.9398)
			(end 0.508 0.9398)
			(stroke
				(width 0.1524)
				(type default)
			)
			(layer "B.SilkS")
		)
		(fp_line
			(start -0.508 -0.9398)
			(end 0.508 -0.9398)
			(stroke
				(width 0.1524)
				(type default)
			)
			(layer "B.SilkS")
		)
		(fp_rect
			(start 0.508 0.9398)
			(end -0.508 -0.9398)
			(stroke
				(width 0)
				(type default)
			)
			(fill no)
			(layer "B.CrtYd")
		)
		(fp_rect
			(start 0.508 0.9398)
			(end -0.508 -0.9398)
			(stroke
				(width 0)
				(type default)
			)
			(fill no)
			(layer "B.Fab")
		)
		(pad "1" smd custom
			(at 0 -0.4445 270)
			(size 0.1397 0.1397)
			(layers "B.Cu" "B.Mask" "B.Paste")
			(net "GND")
			(options
				(clearance outline)
				(anchor circle)
			)
			(primitives
				(gr_poly
					(pts
						(arc
							(start -0.1778 0.2794)
							(mid -0.249642 0.249642)
							(end -0.2794 0.1778)
						)
						(arc
							(start -0.2794 -0.1778)
							(mid -0.249642 -0.249642)
							(end -0.1778 -0.2794)
						)
						(arc
							(start 0.1778 -0.2794)
							(mid 0.249642 -0.249642)
							(end 0.2794 -0.1778)
						)
						(arc
							(start 0.2794 0.1778)
							(mid 0.249642 0.249642)
							(end 0.1778 0.2794)
						)
					)
					(width 0)
					(fill yes)
				)
			)
		)
		(pad "2" smd custom
			(at 0 0.4445 270)
			(size 0.1397 0.1397)
			(layers "B.Cu" "B.Mask" "B.Paste")
			(net "RMII_BMC_RX_ER")
			(options
				(clearance outline)
				(anchor circle)
			)
			(primitives
				(gr_poly
					(pts
						(arc
							(start -0.1778 0.2794)
							(mid -0.249642 0.249642)
							(end -0.2794 0.1778)
						)
						(arc
							(start -0.2794 -0.1778)
							(mid -0.249642 -0.249642)
							(end -0.1778 -0.2794)
						)
						(arc
							(start 0.1778 -0.2794)
							(mid 0.249642 -0.249642)
							(end 0.2794 -0.1778)
						)
						(arc
							(start 0.2794 0.1778)
							(mid 0.249642 0.249642)
							(end 0.1778 0.2794)
						)
					)
					(width 0)
					(fill yes)
				)
			)
		)
	)
	(footprint ""
		(layer "B.Cu")
		(at 32.6263 -122.29338)
		(property "Reference" "TP306"
			(at 0 0 0)
			(layer "B.SilkS")
			(hide yes)
			(effects
				(font
					(size 1.27 1.27)
				)
				(justify mirror)
			)
		)
		(property "Value" "TPAD28-2-GP"
			(at 0.0127 -1.6637 0)
			(unlocked yes)
			(layer "B.Fab")
			(hide yes)
			(effects
				(font
					(size 1.016 1.016)
					(thickness 0.1524)
				)
				(justify mirror)
			)
		)
		(property "Device Type" "TPAD28"
			(at 0.0127 -3.1877 0)
			(unlocked yes)
			(layer "B.Fab")
			(hide yes)
			(effects
				(font
					(size 1.016 1.016)
					(thickness 0.1524)
				)
				(justify mirror)
			)
		)
		(duplicate_pad_numbers_are_jumpers no)
		(fp_poly
			(pts
				(arc
					(start 0.3556 0)
					(mid -0.3556 0)
					(end 0.3556 0)
				)
			)
			(stroke
				(width 0)
				(type default)
			)
			(fill no)
			(layer "B.CrtYd")
		)
		(fp_poly
			(pts
				(arc
					(start 0.6096 0)
					(mid -0.6096 0)
					(end 0.6096 0)
				)
			)
			(stroke
				(width 0)
				(type default)
			)
			(fill no)
			(layer "B.Fab")
		)
		(pad "1" smd circle
			(at 0 0 180)
			(size 0.7112 0.7112)
			(layers "B.Cu" "B.Mask" "B.Paste")
			(net "TP_GPIOD1")
		)
	)
	(footprint ""
		(layer "B.Cu")
		(at 158.6992 -91.9734 90)
		(property "Reference" "C731"
			(at 0 0 90)
			(layer "B.SilkS")
			(hide yes)
			(effects
				(font
					(size 1.27 1.27)
				)
				(justify mirror)
			)
		)
		(property "Value" "SC10U16V5KX-1-GP"
			(at 0.0762 -6.1214 90)
			(unlocked yes)
			(layer "B.Fab")
			(hide yes)
			(effects
				(font
					(size 1.016 1.016)
					(thickness 0.1524)
				)
				(justify mirror)
			)
		)
		(property "Device Type" "C805H54"
			(at 0.0762 -8.1534 90)
			(unlocked yes)
			(layer "B.Fab")
			(hide yes)
			(effects
				(font
					(size 1.016 1.016)
					(thickness 0.1524)
				)
				(justify mirror)
			)
		)
		(duplicate_pad_numbers_are_jumpers no)
		(fp_line
			(start -0.635 0)
			(end 0.635 0)
			(stroke
				(width 0.508)
				(type default)
			)
			(layer "B.SilkS")
		)
		(fp_rect
			(start 0.9652 1.778)
			(end -0.9652 -1.778)
			(stroke
				(width 0)
				(type default)
			)
			(fill no)
			(layer "B.CrtYd")
		)
		(fp_poly
			(pts
				(xy 0.9652 -1.778) (xy -0.9652 -1.778) (xy -0.9652 1.778) (xy 0.9652 1.778)
			)
			(stroke
				(width 0)
				(type default)
			)
			(fill no)
			(layer "B.Fab")
		)
		(pad "1" smd rect
			(at 0 -0.9652 270)
			(size 1.397 1.143)
			(layers "B.Cu" "B.Mask" "B.Paste")
			(net "P1V8_CLKGEN")
		)
		(pad "2" smd rect
			(at 0 0.9652 270)
			(size 1.397 1.143)
			(layers "B.Cu" "B.Mask" "B.Paste")
			(net "GND")
		)
	)
)
